(kicad_pcb
	(version 20241229)
	(generator "pcbnew")
	(generator_version "9.0")
	(general
		(thickness 1.599998)
		(legacy_teardrops no)
	)
	(paper "A4")
	(title_block
		(title "Artix - Datacenter Secure Control Module (DC-SCM)")
		(date "2024-11-06")
		(rev "1.1.3")
		(comment 9 "footprints 267-271 of 544")
	)
	(layers
		(0 "F.Cu" signal)
		(4 "In1.Cu" signal)
		(6 "In2.Cu" signal)
		(8 "In3.Cu" signal)
		(10 "In4.Cu" signal)
		(12 "In5.Cu" signal)
		(14 "In6.Cu" signal)
		(2 "B.Cu" signal)
		(9 "F.Adhes" user "F.Adhesive")
		(11 "B.Adhes" user "B.Adhesive")
		(13 "F.Paste" user)
		(15 "B.Paste" user)
		(5 "F.SilkS" user "F.Silkscreen")
		(7 "B.SilkS" user "B.Silkscreen")
		(1 "F.Mask" user)
		(3 "B.Mask" user)
		(17 "Dwgs.User" user "User.Drawings")
		(19 "Cmts.User" user "User.Comments")
		(21 "Eco1.User" user "User.Eco1")
		(23 "Eco2.User" user "User.Eco2")
		(25 "Edge.Cuts" user)
		(27 "Margin" user)
		(31 "F.CrtYd" user "F.Courtyard")
		(29 "B.CrtYd" user "B.Courtyard")
		(35 "F.Fab" user)
		(33 "B.Fab" user)
	)
	(footprint "antmicro-footprints:C_1210_3225Metric"
		(layer "B.Cu")
		(at 85 133.6 90)
		(descr "Capacitor SMD 1210")
		(tags "capacitor SMD 1210")
		(property "Reference" "C92"
			(at 2.1 -1.1 180)
			(layer "B.SilkS")
			(effects
				(font
					(size 0.7 0.7)
					(thickness 0.15)
				)
				(justify right bottom mirror)
			)
		)
		(property "Value" "C_47u_1210"
			(at 0 -2.749 90)
			(layer "B.Fab")
			(effects
				(font
					(size 0.7 0.7)
					(thickness 0.15)
				)
				(justify right bottom mirror)
			)
		)
		(property "Datasheet" "https://www.kemet.com/en/us/capacitors/product/C1210C476K8RACTU.html"
			(at 0 0 90)
			(layer "F.Fab")
			(hide yes)
			(effects
				(font
					(size 1.27 1.27)
					(thickness 0.15)
				)
			)
		)
		(property "Description" "SMD Multilayer Ceramic Capacitor, 47 µF, 10 V, 1210 [3225 Metric], ± 10%, X7R, C Series KEMET"
			(at 0 0 90)
			(layer "F.Fab")
			(hide yes)
			(effects
				(font
					(size 1.27 1.27)
					(thickness 0.15)
				)
			)
		)
		(property "Author" "Antmicro"
			(at 218.6 48.6 0)
			(layer "B.Fab")
			(hide yes)
			(effects
				(font
					(size 1 1)
					(thickness 0.15)
				)
				(justify mirror)
			)
		)
		(property "Dielectric" ""
			(at 218.6 48.6 0)
			(layer "B.Fab")
			(hide yes)
			(effects
				(font
					(size 1 1)
					(thickness 0.15)
				)
				(justify mirror)
			)
		)
		(property "License" "Apache-2.0"
			(at 218.6 48.6 0)
			(layer "B.Fab")
			(hide yes)
			(effects
				(font
					(size 1 1)
					(thickness 0.15)
				)
				(justify mirror)
			)
		)
		(property "MPN" "C1210C476K8RACTU"
			(at 218.6 48.6 0)
			(layer "B.Fab")
			(hide yes)
			(effects
				(font
					(size 1 1)
					(thickness 0.15)
				)
				(justify mirror)
			)
		)
		(property "Manufacturer" "KEMET"
			(at 218.6 48.6 0)
			(layer "B.Fab")
			(hide yes)
			(effects
				(font
					(size 1 1)
					(thickness 0.15)
				)
				(justify mirror)
			)
		)
		(property "Public" "False"
			(at 218.6 48.6 0)
			(layer "B.Fab")
			(hide yes)
			(effects
				(font
					(size 1 1)
					(thickness 0.15)
				)
				(justify mirror)
			)
		)
		(property "Val" "47u"
			(at 218.6 48.6 0)
			(layer "B.Fab")
			(hide yes)
			(effects
				(font
					(size 1 1)
					(thickness 0.15)
				)
				(justify mirror)
			)
		)
		(property "Voltage" ""
			(at 218.6 48.6 0)
			(layer "B.Fab")
			(hide yes)
			(effects
				(font
					(size 1 1)
					(thickness 0.15)
				)
				(justify mirror)
			)
		)
		(property "DNP" ""
			(at 0 0 90)
			(unlocked yes)
			(layer "B.Fab")
			(hide yes)
			(effects
				(font
					(size 1 1)
					(thickness 0.15)
				)
				(justify mirror)
			)
		)
		(sheetname "/FPGA banks 13-16/")
		(sheetfile "fpga-banks-13-16.kicad_sch")
		(attr smd)
		(fp_line
			(start -0.3 -1.39)
			(end 0.3 -1.39)
			(stroke
				(width 0.15)
				(type solid)
			)
			(layer "B.SilkS")
		)
		(fp_line
			(start -0.3 1.39)
			(end 0.3 1.39)
			(stroke
				(width 0.15)
				(type solid)
			)
			(layer "B.SilkS")
		)
		(fp_rect
			(start -2.1 1.75)
			(end 2.1 -1.75)
			(stroke
				(width 0.05)
				(type solid)
			)
			(fill no)
			(layer "B.CrtYd")
		)
		(fp_rect
			(start -1.6 1.25)
			(end 1.6 -1.25)
			(stroke
				(width 0.15)
				(type solid)
			)
			(fill no)
			(layer "B.Fab")
		)
		(pad "1" smd rect
			(at -1.145 0 90)
			(size 1.52 3.05)
			(layers "B.Cu" "B.Mask" "B.Paste")
			(net 1 "GND")
			(pintype "passive")
		)
		(pad "2" smd rect
			(at 1.145 0 90)
			(size 1.52 3.05)
			(layers "B.Cu" "B.Mask" "B.Paste")
			(net 2 "VCC3V3")
			(pintype "passive")
		)
	)
	(footprint "antmicro-footprints:C_1210_3225Metric"
		(layer "B.Cu")
		(at 112.8 98.5 180)
		(descr "Capacitor SMD 1210")
		(tags "capacitor SMD 1210")
		(property "Reference" "C95"
			(at -2.9 1.1 90)
			(layer "B.SilkS")
			(effects
				(font
					(size 0.7 0.7)
					(thickness 0.15)
				)
				(justify left bottom mirror)
			)
		)
		(property "Value" "C_47u_1210"
			(at 0 -2.749 0)
			(layer "B.Fab")
			(effects
				(font
					(size 0.7 0.7)
					(thickness 0.15)
				)
				(justify left bottom mirror)
			)
		)
		(property "Datasheet" "https://www.kemet.com/en/us/capacitors/product/C1210C476K8RACTU.html"
			(at 0 0 180)
			(layer "F.Fab")
			(hide yes)
			(effects
				(font
					(size 1.27 1.27)
					(thickness 0.15)
				)
			)
		)
		(property "Description" "SMD Multilayer Ceramic Capacitor, 47 µF, 10 V, 1210 [3225 Metric], ± 10%, X7R, C Series KEMET"
			(at 0 0 180)
			(layer "F.Fab")
			(hide yes)
			(effects
				(font
					(size 1.27 1.27)
					(thickness 0.15)
				)
			)
		)
		(property "Author" "Antmicro"
			(at 225.6 197 0)
			(layer "B.Fab")
			(hide yes)
			(effects
				(font
					(size 1 1)
					(thickness 0.15)
				)
				(justify mirror)
			)
		)
		(property "Dielectric" ""
			(at 225.6 197 0)
			(layer "B.Fab")
			(hide yes)
			(effects
				(font
					(size 1 1)
					(thickness 0.15)
				)
				(justify mirror)
			)
		)
		(property "License" "Apache-2.0"
			(at 225.6 197 0)
			(layer "B.Fab")
			(hide yes)
			(effects
				(font
					(size 1 1)
					(thickness 0.15)
				)
				(justify mirror)
			)
		)
		(property "MPN" "C1210C476K8RACTU"
			(at 225.6 197 0)
			(layer "B.Fab")
			(hide yes)
			(effects
				(font
					(size 1 1)
					(thickness 0.15)
				)
				(justify mirror)
			)
		)
		(property "Manufacturer" "KEMET"
			(at 225.6 197 0)
			(layer "B.Fab")
			(hide yes)
			(effects
				(font
					(size 1 1)
					(thickness 0.15)
				)
				(justify mirror)
			)
		)
		(property "Public" "False"
			(at 225.6 197 0)
			(layer "B.Fab")
			(hide yes)
			(effects
				(font
					(size 1 1)
					(thickness 0.15)
				)
				(justify mirror)
			)
		)
		(property "Val" "47u"
			(at 225.6 197 0)
			(layer "B.Fab")
			(hide yes)
			(effects
				(font
					(size 1 1)
					(thickness 0.15)
				)
				(justify mirror)
			)
		)
		(property "Voltage" ""
			(at 225.6 197 0)
			(layer "B.Fab")
			(hide yes)
			(effects
				(font
					(size 1 1)
					(thickness 0.15)
				)
				(justify mirror)
			)
		)
		(sheetname "/FPGA banks 13-16/")
		(sheetfile "fpga-banks-13-16.kicad_sch")
		(attr smd)
		(fp_line
			(start -0.3 1.39)
			(end 0.3 1.39)
			(stroke
				(width 0.15)
				(type solid)
			)
			(layer "B.SilkS")
		)
		(fp_line
			(start -0.3 -1.39)
			(end 0.3 -1.39)
			(stroke
				(width 0.15)
				(type solid)
			)
			(layer "B.SilkS")
		)
		(fp_rect
			(start -2.1 1.75)
			(end 2.1 -1.75)
			(stroke
				(width 0.05)
				(type solid)
			)
			(fill no)
			(layer "B.CrtYd")
		)
		(fp_rect
			(start -1.6 1.25)
			(end 1.6 -1.25)
			(stroke
				(width 0.15)
				(type solid)
			)
			(fill no)
			(layer "B.Fab")
		)
		(pad "1" smd rect
			(at -1.145 0 180)
			(size 1.52 3.05)
			(layers "B.Cu" "B.Mask" "B.Paste")
			(net 1 "GND")
			(pintype "passive")
		)
		(pad "2" smd rect
			(at 1.145 0 180)
			(size 1.52 3.05)
			(layers "B.Cu" "B.Mask" "B.Paste")
			(net 2 "VCC3V3")
			(pintype "passive")
		)
	)
	(footprint "antmicro-footprints:C_1210_3225Metric"
		(layer "B.Cu")
		(at 90.5 148.9)
		(descr "Capacitor SMD 1210")
		(tags "capacitor SMD 1210")
		(property "Reference" "C96"
			(at -1.1 -1.8 0)
			(layer "B.SilkS")
			(effects
				(font
					(size 0.7 0.7)
					(thickness 0.15)
				)
				(justify right bottom mirror)
			)
		)
		(property "Value" "C_47u_1210"
			(at 0 -2.749 0)
			(layer "B.Fab")
			(effects
				(font
					(size 0.7 0.7)
					(thickness 0.15)
				)
				(justify right bottom mirror)
			)
		)
		(property "Datasheet" "https://www.kemet.com/en/us/capacitors/product/C1210C476K8RACTU.html"
			(at 0 0 0)
			(layer "F.Fab")
			(hide yes)
			(effects
				(font
					(size 1.27 1.27)
					(thickness 0.15)
				)
			)
		)
		(property "Description" "SMD Multilayer Ceramic Capacitor, 47 µF, 10 V, 1210 [3225 Metric], ± 10%, X7R, C Series KEMET"
			(at 0 0 0)
			(layer "F.Fab")
			(hide yes)
			(effects
				(font
					(size 1.27 1.27)
					(thickness 0.15)
				)
			)
		)
		(property "Author" "Antmicro"
			(at 0 0 0)
			(layer "B.Fab")
			(hide yes)
			(effects
				(font
					(size 1 1)
					(thickness 0.15)
				)
				(justify mirror)
			)
		)
		(property "Dielectric" ""
			(at 0 0 0)
			(layer "B.Fab")
			(hide yes)
			(effects
				(font
					(size 1 1)
					(thickness 0.15)
				)
				(justify mirror)
			)
		)
		(property "License" "Apache-2.0"
			(at 0 0 0)
			(layer "B.Fab")
			(hide yes)
			(effects
				(font
					(size 1 1)
					(thickness 0.15)
				)
				(justify mirror)
			)
		)
		(property "MPN" "C1210C476K8RACTU"
			(at 0 0 0)
			(layer "B.Fab")
			(hide yes)
			(effects
				(font
					(size 1 1)
					(thickness 0.15)
				)
				(justify mirror)
			)
		)
		(property "Manufacturer" "KEMET"
			(at 0 0 0)
			(layer "B.Fab")
			(hide yes)
			(effects
				(font
					(size 1 1)
					(thickness 0.15)
				)
				(justify mirror)
			)
		)
		(property "Public" "False"
			(at 0 0 0)
			(layer "B.Fab")
			(hide yes)
			(effects
				(font
					(size 1 1)
					(thickness 0.15)
				)
				(justify mirror)
			)
		)
		(property "Val" "47u"
			(at 0 0 0)
			(layer "B.Fab")
			(hide yes)
			(effects
				(font
					(size 1 1)
					(thickness 0.15)
				)
				(justify mirror)
			)
		)
		(property "Voltage" ""
			(at 0 0 0)
			(layer "B.Fab")
			(hide yes)
			(effects
				(font
					(size 1 1)
					(thickness 0.15)
				)
				(justify mirror)
			)
		)
		(sheetname "/FPGA banks 34-35 & CFG/")
		(sheetfile "fpga-banks-34-25-cfg.kicad_sch")
		(attr smd)
		(fp_line
			(start -0.3 -1.39)
			(end 0.3 -1.39)
			(stroke
				(width 0.15)
				(type solid)
			)
			(layer "B.SilkS")
		)
		(fp_line
			(start -0.3 1.39)
			(end 0.3 1.39)
			(stroke
				(width 0.15)
				(type solid)
			)
			(layer "B.SilkS")
		)
		(fp_rect
			(start -2.1 1.75)
			(end 2.1 -1.75)
			(stroke
				(width 0.05)
				(type solid)
			)
			(fill no)
			(layer "B.CrtYd")
		)
		(fp_rect
			(start -1.6 1.25)
			(end 1.6 -1.25)
			(stroke
				(width 0.15)
				(type solid)
			)
			(fill no)
			(layer "B.Fab")
		)
		(pad "1" smd rect
			(at -1.145 0)
			(size 1.52 3.05)
			(layers "B.Cu" "B.Mask" "B.Paste")
			(net 1 "GND")
			(pintype "passive")
		)
		(pad "2" smd rect
			(at 1.145 0)
			(size 1.52 3.05)
			(layers "B.Cu" "B.Mask" "B.Paste")
			(net 3 "VCC1V35")
			(pintype "passive")
		)
	)
	(footprint "antmicro-footprints:C_0603_1608Metric"
		(layer "B.Cu")
		(at 91.3 119.3 90)
		(descr "Capacitor SMD 0603")
		(tags "capacitor 0603")
		(property "Reference" "C97"
			(at -0.7 -0.6 90)
			(layer "B.SilkS")
			(effects
				(font
					(size 0.7 0.7)
					(thickness 0.15)
				)
				(justify right bottom mirror)
			)
		)
		(property "Value" "C_4u7_0603"
			(at 0 -1.6 90)
			(layer "B.Fab")
			(effects
				(font
					(size 0.7 0.7)
					(thickness 0.15)
				)
				(justify right bottom mirror)
			)
		)
		(property "Datasheet" "https://product.tdk.com/en/search/capacitor/ceramic/mlcc/info?part_no=C1608X5R1V475M080AC"
			(at 0 0 90)
			(layer "F.Fab")
			(hide yes)
			(effects
				(font
					(size 1.27 1.27)
					(thickness 0.15)
				)
			)
		)
		(property "Description" "SMD Multilayer Ceramic Capacitor, 4.7 µF, 35 V, 0603 [1608 Metric], ± 20%, X5R, C"
			(at 0 0 90)
			(layer "F.Fab")
			(hide yes)
			(effects
				(font
					(size 1.27 1.27)
					(thickness 0.15)
				)
			)
		)
		(property "Author" "Antmicro"
			(at 210.6 28 0)
			(layer "B.Fab")
			(hide yes)
			(effects
				(font
					(size 1 1)
					(thickness 0.15)
				)
				(justify mirror)
			)
		)
		(property "Dielectric" ""
			(at 210.6 28 0)
			(layer "B.Fab")
			(hide yes)
			(effects
				(font
					(size 1 1)
					(thickness 0.15)
				)
				(justify mirror)
			)
		)
		(property "License" "Apache-2.0"
			(at 210.6 28 0)
			(layer "B.Fab")
			(hide yes)
			(effects
				(font
					(size 1 1)
					(thickness 0.15)
				)
				(justify mirror)
			)
		)
		(property "MPN" "C1608X5R1V475M080AC"
			(at 210.6 28 0)
			(layer "B.Fab")
			(hide yes)
			(effects
				(font
					(size 1 1)
					(thickness 0.15)
				)
				(justify mirror)
			)
		)
		(property "Manufacturer" "TDK"
			(at 210.6 28 0)
			(layer "B.Fab")
			(hide yes)
			(effects
				(font
					(size 1 1)
					(thickness 0.15)
				)
				(justify mirror)
			)
		)
		(property "Val" "4u7"
			(at 210.6 28 0)
			(layer "B.Fab")
			(hide yes)
			(effects
				(font
					(size 1 1)
					(thickness 0.15)
				)
				(justify mirror)
			)
		)
		(property "Voltage" ""
			(at 210.6 28 0)
			(layer "B.Fab")
			(hide yes)
			(effects
				(font
					(size 1 1)
					(thickness 0.15)
				)
				(justify mirror)
			)
		)
		(sheetname "/FPGA banks 34-35 & CFG/")
		(sheetfile "fpga-banks-34-25-cfg.kicad_sch")
		(attr smd)
		(fp_line
			(start -0.15 -0.4)
			(end 0.15 -0.4)
			(stroke
				(width 0.15)
				(type solid)
			)
			(layer "B.SilkS")
		)
		(fp_line
			(start -0.15 0.4)
			(end 0.15 0.4)
			(stroke
				(width 0.15)
				(type solid)
			)
			(layer "B.SilkS")
		)
		(fp_rect
			(start -1.25 0.65)
			(end 1.25 -0.65)
			(stroke
				(width 0.05)
				(type solid)
			)
			(fill no)
			(layer "B.CrtYd")
		)
		(fp_rect
			(start -0.8 0.4)
			(end 0.8 -0.4)
			(stroke
				(width 0.15)
				(type solid)
			)
			(fill no)
			(layer "B.Fab")
		)
		(pad "1" smd roundrect
			(at -0.7 0 90)
			(size 0.8 1)
			(layers "B.Cu" "B.Mask" "B.Paste")
			(roundrect_rratio 0.2)
			(net 1 "GND")
			(pintype "passive")
		)
		(pad "2" smd roundrect
			(at 0.7 0 90)
			(size 0.8 1)
			(layers "B.Cu" "B.Mask" "B.Paste")
			(roundrect_rratio 0.2)
			(net 2 "VCC3V3")
			(pintype "passive")
		)
	)
	(footprint "antmicro-footprints:C_0603_1608Metric"
		(layer "B.Cu")
		(at 92.8 133.6 90)
		(descr "Capacitor SMD 0603")
		(tags "capacitor 0603")
		(property "Reference" "C98"
			(at -3.2 0.3 90)
			(layer "B.SilkS")
			(effects
				(font
					(size 0.7 0.7)
					(thickness 0.15)
				)
				(justify right bottom mirror)
			)
		)
		(property "Value" "C_4u7_0603"
			(at 0 -1.6 90)
			(layer "B.Fab")
			(effects
				(font
					(size 0.7 0.7)
					(thickness 0.15)
				)
				(justify right bottom mirror)
			)
		)
		(property "Datasheet" "https://product.tdk.com/en/search/capacitor/ceramic/mlcc/info?part_no=C1608X5R1V475M080AC"
			(at 0 0 90)
			(layer "F.Fab")
			(hide yes)
			(effects
				(font
					(size 1.27 1.27)
					(thickness 0.15)
				)
			)
		)
		(property "Description" "SMD Multilayer Ceramic Capacitor, 4.7 µF, 35 V, 0603 [1608 Metric], ± 20%, X5R, C"
			(at 0 0 90)
			(layer "F.Fab")
			(hide yes)
			(effects
				(font
					(size 1.27 1.27)
					(thickness 0.15)
				)
			)
		)
		(property "Author" "Antmicro"
			(at 226.4 40.8 0)
			(layer "B.Fab")
			(hide yes)
			(effects
				(font
					(size 1 1)
					(thickness 0.15)
				)
				(justify mirror)
			)
		)
		(property "Dielectric" ""
			(at 226.4 40.8 0)
			(layer "B.Fab")
			(hide yes)
			(effects
				(font
					(size 1 1)
					(thickness 0.15)
				)
				(justify mirror)
			)
		)
		(property "License" "Apache-2.0"
			(at 226.4 40.8 0)
			(layer "B.Fab")
			(hide yes)
			(effects
				(font
					(size 1 1)
					(thickness 0.15)
				)
				(justify mirror)
			)
		)
		(property "MPN" "C1608X5R1V475M080AC"
			(at 226.4 40.8 0)
			(layer "B.Fab")
			(hide yes)
			(effects
				(font
					(size 1 1)
					(thickness 0.15)
				)
				(justify mirror)
			)
		)
		(property "Manufacturer" "TDK"
			(at 226.4 40.8 0)
			(layer "B.Fab")
			(hide yes)
			(effects
				(font
					(size 1 1)
					(thickness 0.15)
				)
				(justify mirror)
			)
		)
		(property "Val" "4u7"
			(at 226.4 40.8 0)
			(layer "B.Fab")
			(hide yes)
			(effects
				(font
					(size 1 1)
					(thickness 0.15)
				)
				(justify mirror)
			)
		)
		(property "Voltage" ""
			(at 226.4 40.8 0)
			(layer "B.Fab")
			(hide yes)
			(effects
				(font
					(size 1 1)
					(thickness 0.15)
				)
				(justify mirror)
			)
		)
		(property "DNP" ""
			(at 0 0 90)
			(unlocked yes)
			(layer "B.Fab")
			(hide yes)
			(effects
				(font
					(size 1 1)
					(thickness 0.15)
				)
				(justify mirror)
			)
		)
		(sheetname "/FPGA banks 13-16/")
		(sheetfile "fpga-banks-13-16.kicad_sch")
		(attr smd)
		(fp_line
			(start -0.15 -0.4)
			(end 0.15 -0.4)
			(stroke
				(width 0.15)
				(type solid)
			)
			(layer "B.SilkS")
		)
		(fp_line
			(start -0.15 0.4)
			(end 0.15 0.4)
			(stroke
				(width 0.15)
				(type solid)
			)
			(layer "B.SilkS")
		)
		(fp_rect
			(start -1.25 0.65)
			(end 1.25 -0.65)
			(stroke
				(width 0.05)
				(type solid)
			)
			(fill no)
			(layer "B.CrtYd")
		)
		(fp_rect
			(start -0.8 0.4)
			(end 0.8 -0.4)
			(stroke
				(width 0.15)
				(type solid)
			)
			(fill no)
			(layer "B.Fab")
		)
		(pad "1" smd roundrect
			(at -0.7 0 90)
			(size 0.8 1)
			(layers "B.Cu" "B.Mask" "B.Paste")
			(roundrect_rratio 0.2)
			(net 1 "GND")
			(pintype "passive")
		)
		(pad "2" smd roundrect
			(at 0.7 0 90)
			(size 0.8 1)
			(layers "B.Cu" "B.Mask" "B.Paste")
			(roundrect_rratio 0.2)
			(net 2 "VCC3V3")
			(pintype "passive")
		)
	)
)
